# T6G (Grand Teton) — schematic netlist excerpt (pin names and nets, part order shuffled) for the footprints in the layout excerpt that follows; sources: Cadence DE-HDL packaged netlist, KiCad conversion of 04192023_DAF0TMB3IC0_F0TG_MB_C_brd_V02_OCP.brd

U17  M24M02DRMN6TP  M24M02-DRMN6TP IC  pkg SOIC8XH  page 311
  DU1  = NC
  DU2  = NC
  E2  = U17_E2
  VSS  = GND
  SDA  = SMB_RT_CPU0_P3_ROM_SDA
  SCL  = SMB_RT_CPU0_P3_ROM_SCL
  WC_N  = GND
  VCC  = P1V8_CPU0_RT_1D

C6725  Q_CAP_DIFFBUS  DIFF BUS_0.22UF 6.3V 20% X6S  pkg C0201  page 352 : \1\ = P5E_CPU1_P3_TX_BUF_C_DP<0> ; \2\ = P5E_CPU1_P3_TX_BUF_DP<0>
C657  Q_CAP  0.1UF 10V 10% X7S  pkg C0201  page 290 : A = P0V9_CPU0_RT1_2A ; B = GND

(kicad_pcb
	(version 20260206)
	(generator "pcbnew")
	(generator_version "10.0")
	(general
		(thickness 1.6)
		(legacy_teardrops no)
	)
	(paper "A4")
	(title_block
		(title "04192023_DAF0TMB3IC0_F0TG_MB_C_brd_V02_OCP.brd")
		(comment 1 "Grand Teton / footprints 8093-8095 of 8354")
	)
	(layers
		(0 "F.Cu" signal "TOP")
		(4 "In1.Cu" signal "GND")
		(6 "In2.Cu" signal "IN1")
		(8 "In3.Cu" signal "GND1")
		(10 "In4.Cu" signal "IN2")
		(12 "In5.Cu" signal "GND2")
		(14 "In6.Cu" signal "IN3")
		(16 "In7.Cu" signal "GND3")
		(18 "In8.Cu" signal "VCC")
		(20 "In9.Cu" signal "VCC1")
		(22 "In10.Cu" signal "GND4")
		(24 "In11.Cu" signal "IN4")
		(26 "In12.Cu" signal "GND5")
		(28 "In13.Cu" signal "IN5")
		(30 "In14.Cu" signal "GND6")
		(32 "In15.Cu" signal "IN6")
		(34 "In16.Cu" signal "GND7")
		(2 "B.Cu" signal "BOTTOM")
		(9 "F.Adhes" user "F.Adhesive")
		(11 "B.Adhes" user "B.Adhesive")
		(13 "F.Paste" user "Package Geometry/Pastemask Top")
		(15 "B.Paste" user "Package Geometry/Pastemask Bottom")
		(5 "F.SilkS" user "Ref Des/Silkscreen Top")
		(7 "B.SilkS" user "Ref Des/Silkscreen Bottom")
		(1 "F.Mask" user "Board Geometry/Soldermask Top")
		(3 "B.Mask" user "Board Geometry/Soldermask Bottom")
		(17 "Dwgs.User" user "User.Drawings")
		(19 "Cmts.User" user "User.Comments")
		(21 "Eco1.User" user "User.Eco1")
		(23 "Eco2.User" user "User.Eco2")
		(25 "Edge.Cuts" user "Board Geometry/Outline")
		(27 "Margin" user)
		(31 "F.CrtYd" user "Package Geometry/Place Bound Top")
		(29 "B.CrtYd" user "Package Geometry/Place Bound Bottom")
		(35 "F.Fab" user "Ref Des/Assembly Top")
		(33 "B.Fab" user "Ref Des/Assembly Bottom")
	)
	(footprint ""
		(layer "B.Cu")
		(at 373.976646 -424.523916)
		(property "Reference" "U17"
			(at 1.562354 -3.185414 0)
			(unlocked yes)
			(layer "B.SilkS")
			(effects
				(font
					(size 0.7874 0.5842)
					(thickness 0.1524)
				)
				(justify left mirror)
			)
		)
		(property "Value" ""
			(at 0 0 0)
			(layer "B.Fab")
			(effects
				(font
					(size 1.27 1.27)
				)
				(justify mirror)
			)
		)
		(duplicate_pad_numbers_are_jumpers no)
		(fp_line
			(start -1.8288 -2.500122)
			(end -1.077722 -2.500122)
			(stroke
				(width 0.1524)
				(type default)
			)
			(layer "B.SilkS")
		)
		(fp_line
			(start -1.8288 2.500122)
			(end -1.8288 -2.500122)
			(stroke
				(width 0.1524)
				(type default)
			)
			(layer "B.SilkS")
		)
		(fp_line
			(start -1.077722 -2.500122)
			(end 0 -1.4224)
			(stroke
				(width 0.1524)
				(type default)
			)
			(layer "B.SilkS")
		)
		(fp_line
			(start 0 -1.4224)
			(end 1.077722 -2.500122)
			(stroke
				(width 0.1524)
				(type default)
			)
			(layer "B.SilkS")
		)
		(fp_line
			(start 1.077722 -2.500122)
			(end 1.8288 -2.500122)
			(stroke
				(width 0.1524)
				(type default)
			)
			(layer "B.SilkS")
		)
		(fp_line
			(start 1.8288 -2.500122)
			(end 1.8288 2.500122)
			(stroke
				(width 0.1524)
				(type default)
			)
			(layer "B.SilkS")
		)
		(fp_line
			(start 1.8288 2.500122)
			(end -1.8288 2.500122)
			(stroke
				(width 0.1524)
				(type default)
			)
			(layer "B.SilkS")
		)
		(fp_poly
			(pts
				(xy 2.107438 -3.61823) (xy 3.123438 -3.61823) (xy 2.615438 -2.60223)
			)
			(stroke
				(width 0)
				(type default)
			)
			(fill yes)
			(layer "B.SilkS")
		)
		(fp_line
			(start -1.999996 -2.500122)
			(end 1.999996 -2.500122)
			(stroke
				(width 0.1)
				(type default)
			)
			(layer "B.Fab")
		)
		(fp_line
			(start -1.999996 2.500122)
			(end -1.999996 -2.500122)
			(stroke
				(width 0.1)
				(type default)
			)
			(layer "B.Fab")
		)
		(fp_line
			(start 1.999996 -2.500122)
			(end 1.999996 2.500122)
			(stroke
				(width 0.1)
				(type default)
			)
			(layer "B.Fab")
		)
		(fp_line
			(start 1.999996 2.500122)
			(end -1.999996 2.500122)
			(stroke
				(width 0.1)
				(type default)
			)
			(layer "B.Fab")
		)
		(fp_poly
			(pts
				(xy 4.5085 -2.413) (xy 4.5085 -1.397) (xy 3.4925 -1.905)
			)
			(stroke
				(width 0)
				(type default)
			)
			(fill yes)
			(layer "B.Fab")
		)
		(pad "1" smd rect
			(at 2.599944 -1.905 270)
			(size 0.889 1.27)
			(layers "B.Cu" "B.Mask" "B.Paste")
			(net "Net_10839")
		)
		(pad "2" smd rect
			(at 2.599944 -0.635 270)
			(size 0.889 1.27)
			(layers "B.Cu" "B.Mask" "B.Paste")
			(net "Net_10838")
		)
		(pad "3" smd rect
			(at 2.599944 0.635 270)
			(size 0.889 1.27)
			(layers "B.Cu" "B.Mask" "B.Paste")
			(net "U17_E2")
		)
		(pad "4" smd rect
			(at 2.599944 1.905 270)
			(size 0.889 1.27)
			(layers "B.Cu" "B.Mask" "B.Paste")
			(net "GND")
		)
		(pad "5" smd rect
			(at -2.599944 1.905 270)
			(size 0.889 1.27)
			(layers "B.Cu" "B.Mask" "B.Paste")
			(net "SMB_RT_CPU0_P3_ROM_SDA")
		)
		(pad "6" smd rect
			(at -2.599944 0.635 270)
			(size 0.889 1.27)
			(layers "B.Cu" "B.Mask" "B.Paste")
			(net "SMB_RT_CPU0_P3_ROM_SCL")
		)
		(pad "7" smd rect
			(at -2.599944 -0.635 270)
			(size 0.889 1.27)
			(layers "B.Cu" "B.Mask" "B.Paste")
			(net "GND")
		)
		(pad "8" smd rect
			(at -2.599944 -1.905 270)
			(size 0.889 1.27)
			(layers "B.Cu" "B.Mask" "B.Paste")
			(net "P1V8_CPU0_RT_1D")
		)
	)
	(footprint ""
		(layer "B.Cu")
		(at 336.046064 -396.393162 -90)
		(property "Reference" "C657"
			(at 0 0 90)
			(layer "B.SilkS")
			(hide yes)
			(effects
				(font
					(size 1.27 1.27)
				)
				(justify mirror)
			)
		)
		(property "Value" ""
			(at 0 0 90)
			(layer "B.Fab")
			(effects
				(font
					(size 1.27 1.27)
				)
				(justify mirror)
			)
		)
		(duplicate_pad_numbers_are_jumpers no)
		(fp_line
			(start -0.299974 0.150114)
			(end 0.299974 0.150114)
			(stroke
				(width 0.1)
				(type default)
			)
			(layer "B.Fab")
		)
		(fp_line
			(start 0.299974 0.150114)
			(end 0.299974 -0.150114)
			(stroke
				(width 0.1)
				(type default)
			)
			(layer "B.Fab")
		)
		(fp_line
			(start -0.299974 -0.150114)
			(end -0.299974 0.150114)
			(stroke
				(width 0.1)
				(type default)
			)
			(layer "B.Fab")
		)
		(fp_line
			(start 0.299974 -0.150114)
			(end -0.299974 -0.150114)
			(stroke
				(width 0.1)
				(type default)
			)
			(layer "B.Fab")
		)
		(pad "1" smd rect
			(at 0.2667 0 90)
			(size 0.3048 0.381)
			(layers "B.Cu" "B.Mask" "B.Paste")
			(net "P0V9_CPU0_RT1_2A")
		)
		(pad "2" smd rect
			(at -0.2667 0 90)
			(size 0.3048 0.381)
			(layers "B.Cu" "B.Mask" "B.Paste")
			(net "GND")
		)
	)
	(footprint ""
		(layer "B.Cu")
		(at 117.314726 -408.517344 90)
		(property "Reference" "C6725"
			(at 0 0 90)
			(layer "B.SilkS")
			(hide yes)
			(effects
				(font
					(size 1.27 1.27)
				)
				(justify mirror)
			)
		)
		(property "Value" ""
			(at 0 0 90)
			(layer "B.Fab")
			(effects
				(font
					(size 1.27 1.27)
				)
				(justify mirror)
			)
		)
		(duplicate_pad_numbers_are_jumpers no)
		(fp_line
			(start 0.299974 -0.150114)
			(end -0.299974 -0.150114)
			(stroke
				(width 0.1)
				(type default)
			)
			(layer "B.Fab")
		)
		(fp_line
			(start -0.299974 -0.150114)
			(end -0.299974 0.150114)
			(stroke
				(width 0.1)
				(type default)
			)
			(layer "B.Fab")
		)
		(fp_line
			(start 0.299974 0.150114)
			(end 0.299974 -0.150114)
			(stroke
				(width 0.1)
				(type default)
			)
			(layer "B.Fab")
		)
		(fp_line
			(start -0.299974 0.150114)
			(end 0.299974 0.150114)
			(stroke
				(width 0.1)
				(type default)
			)
			(layer "B.Fab")
		)
		(pad "1" smd rect
			(at 0.2667 0 270)
			(size 0.3048 0.381)
			(layers "B.Cu" "B.Mask" "B.Paste")
			(net "P5E_CPU1_P3_TX_BUF_C_DP<0>")
		)
		(pad "2" smd rect
			(at -0.2667 0 270)
			(size 0.3048 0.381)
			(layers "B.Cu" "B.Mask" "B.Paste")
			(net "P5E_CPU1_P3_TX_BUF_DP<0>")
		)
	)
)
